# T6G (Grand Teton) — schematic netlist excerpt (pin names and nets, part order shuffled) for the footprints in the layout excerpt that follows; sources: Cadence DE-HDL packaged netlist, KiCad conversion of 04192023_DAF0TMB3IC0_F0TG_MB_C_brd_V02_OCP.brd

R1520  Q_RES  0 5% CHIP  pkg 0402LF  page 140 : A = P12V_OCP_V3_2_BUF_EN_R ; B = P3V3_OCP_EN_2_R
PR413  Q_RES  0 5% EMPTY  pkg 0402LF  page 208 : A = PVDD11_S3_P0_PVCC ; B = P3V3_AUX

(kicad_pcb
	(version 20260206)
	(generator "pcbnew")
	(generator_version "10.0")
	(general
		(thickness 1.6)
		(legacy_teardrops no)
	)
	(paper "A4")
	(title_block
		(title "04192023_DAF0TMB3IC0_F0TG_MB_C_brd_V02_OCP.brd")
		(comment 1 "Grand Teton / footprints 2879-2880 of 8354")
	)
	(layers
		(0 "F.Cu" signal "TOP")
		(4 "In1.Cu" signal "GND")
		(6 "In2.Cu" signal "IN1")
		(8 "In3.Cu" signal "GND1")
		(10 "In4.Cu" signal "IN2")
		(12 "In5.Cu" signal "GND2")
		(14 "In6.Cu" signal "IN3")
		(16 "In7.Cu" signal "GND3")
		(18 "In8.Cu" signal "VCC")
		(20 "In9.Cu" signal "VCC1")
		(22 "In10.Cu" signal "GND4")
		(24 "In11.Cu" signal "IN4")
		(26 "In12.Cu" signal "GND5")
		(28 "In13.Cu" signal "IN5")
		(30 "In14.Cu" signal "GND6")
		(32 "In15.Cu" signal "IN6")
		(34 "In16.Cu" signal "GND7")
		(2 "B.Cu" signal "BOTTOM")
		(9 "F.Adhes" user "F.Adhesive")
		(11 "B.Adhes" user "B.Adhesive")
		(13 "F.Paste" user "Package Geometry/Pastemask Top")
		(15 "B.Paste" user "Package Geometry/Pastemask Bottom")
		(5 "F.SilkS" user "Ref Des/Silkscreen Top")
		(7 "B.SilkS" user "Ref Des/Silkscreen Bottom")
		(1 "F.Mask" user "Board Geometry/Soldermask Top")
		(3 "B.Mask" user "Board Geometry/Soldermask Bottom")
		(17 "Dwgs.User" user "User.Drawings")
		(19 "Cmts.User" user "User.Comments")
		(21 "Eco1.User" user "User.Eco1")
		(23 "Eco2.User" user "User.Eco2")
		(25 "Edge.Cuts" user "Board Geometry/Outline")
		(27 "Margin" user)
		(31 "F.CrtYd" user "Package Geometry/Place Bound Top")
		(29 "B.CrtYd" user "Package Geometry/Place Bound Bottom")
		(35 "F.Fab" user "Ref Des/Assembly Top")
		(33 "B.Fab" user "Ref Des/Assembly Bottom")
	)
	(footprint ""
		(layer "F.Cu")
		(at 57.17286 -39.36238 90)
		(property "Reference" "R1520"
			(at 0 0 90)
			(layer "F.SilkS")
			(hide yes)
			(effects
				(font
					(size 1.27 1.27)
				)
			)
		)
		(property "Value" ""
			(at 0 0 90)
			(layer "F.Fab")
			(effects
				(font
					(size 1.27 1.27)
				)
			)
		)
		(duplicate_pad_numbers_are_jumpers no)
		(fp_line
			(start 0.7874 -0.4064)
			(end 0.7874 0.4064)
			(stroke
				(width 0.1524)
				(type default)
			)
			(layer "F.SilkS")
		)
		(fp_line
			(start -0.7874 -0.4064)
			(end 0.7874 -0.4064)
			(stroke
				(width 0.1524)
				(type default)
			)
			(layer "F.SilkS")
		)
		(fp_line
			(start 0.7874 0.4064)
			(end -0.7874 0.4064)
			(stroke
				(width 0.1524)
				(type default)
			)
			(layer "F.SilkS")
		)
		(fp_line
			(start -0.7874 0.4064)
			(end -0.7874 -0.4064)
			(stroke
				(width 0.1524)
				(type default)
			)
			(layer "F.SilkS")
		)
		(fp_line
			(start -0.12065 -0.305054)
			(end -0.12065 -0.2794)
			(stroke
				(width 0.1)
				(type default)
			)
			(layer "F.Fab")
		)
		(fp_line
			(start -0.67945 -0.305054)
			(end -0.12065 -0.305054)
			(stroke
				(width 0.1)
				(type default)
			)
			(layer "F.Fab")
		)
		(fp_line
			(start 0.67945 -0.3048)
			(end 0.67945 0.3048)
			(stroke
				(width 0.1)
				(type default)
			)
			(layer "F.Fab")
		)
		(fp_line
			(start 0.12065 -0.3048)
			(end 0.67945 -0.3048)
			(stroke
				(width 0.1)
				(type default)
			)
			(layer "F.Fab")
		)
		(fp_line
			(start 0.12065 -0.2794)
			(end 0.12065 -0.3048)
			(stroke
				(width 0.1)
				(type default)
			)
			(layer "F.Fab")
		)
		(fp_line
			(start -0.12065 -0.2794)
			(end 0.12065 -0.2794)
			(stroke
				(width 0.1)
				(type default)
			)
			(layer "F.Fab")
		)
		(fp_line
			(start 0.120396 0.2794)
			(end -0.12065 0.2794)
			(stroke
				(width 0.1)
				(type default)
			)
			(layer "F.Fab")
		)
		(fp_line
			(start -0.12065 0.2794)
			(end -0.12065 0.3048)
			(stroke
				(width 0.1)
				(type default)
			)
			(layer "F.Fab")
		)
		(fp_line
			(start 0.67945 0.3048)
			(end 0.120396 0.3048)
			(stroke
				(width 0.1)
				(type default)
			)
			(layer "F.Fab")
		)
		(fp_line
			(start 0.120396 0.3048)
			(end 0.120396 0.2794)
			(stroke
				(width 0.1)
				(type default)
			)
			(layer "F.Fab")
		)
		(fp_line
			(start -0.12065 0.3048)
			(end -0.67945 0.3048)
			(stroke
				(width 0.1)
				(type default)
			)
			(layer "F.Fab")
		)
		(fp_line
			(start -0.67945 0.3048)
			(end -0.67945 -0.305054)
			(stroke
				(width 0.1)
				(type default)
			)
			(layer "F.Fab")
		)
		(pad "1" smd circle
			(at -0.40005 0 90)
			(size 0 0)
			(layers "F.Cu" "F.Mask" "F.Paste")
			(net "P12V_OCP_V3_2_BUF_EN_R")
		)
		(pad "2" smd circle
			(at 0.40005 0 90)
			(size 0 0)
			(layers "F.Cu" "F.Mask" "F.Paste")
			(net "P3V3_OCP_EN_2_R")
		)
	)
	(footprint ""
		(layer "F.Cu")
		(at 417.86937 -353.77628 90)
		(property "Reference" "PR413"
			(at 0 0 90)
			(layer "F.SilkS")
			(hide yes)
			(effects
				(font
					(size 1.27 1.27)
				)
			)
		)
		(property "Value" ""
			(at 0 0 90)
			(layer "F.Fab")
			(effects
				(font
					(size 1.27 1.27)
				)
			)
		)
		(duplicate_pad_numbers_are_jumpers no)
		(fp_line
			(start 0.7874 -0.4064)
			(end 0.7874 0.4064)
			(stroke
				(width 0.1524)
				(type default)
			)
			(layer "F.SilkS")
		)
		(fp_line
			(start -0.7874 -0.4064)
			(end 0.7874 -0.4064)
			(stroke
				(width 0.1524)
				(type default)
			)
			(layer "F.SilkS")
		)
		(fp_line
			(start 0.7874 0.4064)
			(end -0.7874 0.4064)
			(stroke
				(width 0.1524)
				(type default)
			)
			(layer "F.SilkS")
		)
		(fp_line
			(start -0.7874 0.4064)
			(end -0.7874 -0.4064)
			(stroke
				(width 0.1524)
				(type default)
			)
			(layer "F.SilkS")
		)
		(fp_line
			(start -0.12065 -0.305054)
			(end -0.12065 -0.2794)
			(stroke
				(width 0.1)
				(type default)
			)
			(layer "F.Fab")
		)
		(fp_line
			(start -0.67945 -0.305054)
			(end -0.12065 -0.305054)
			(stroke
				(width 0.1)
				(type default)
			)
			(layer "F.Fab")
		)
		(fp_line
			(start 0.67945 -0.3048)
			(end 0.67945 0.3048)
			(stroke
				(width 0.1)
				(type default)
			)
			(layer "F.Fab")
		)
		(fp_line
			(start 0.12065 -0.3048)
			(end 0.67945 -0.3048)
			(stroke
				(width 0.1)
				(type default)
			)
			(layer "F.Fab")
		)
		(fp_line
			(start 0.12065 -0.2794)
			(end 0.12065 -0.3048)
			(stroke
				(width 0.1)
				(type default)
			)
			(layer "F.Fab")
		)
		(fp_line
			(start -0.12065 -0.2794)
			(end 0.12065 -0.2794)
			(stroke
				(width 0.1)
				(type default)
			)
			(layer "F.Fab")
		)
		(fp_line
			(start 0.120396 0.2794)
			(end -0.12065 0.2794)
			(stroke
				(width 0.1)
				(type default)
			)
			(layer "F.Fab")
		)
		(fp_line
			(start -0.12065 0.2794)
			(end -0.12065 0.3048)
			(stroke
				(width 0.1)
				(type default)
			)
			(layer "F.Fab")
		)
		(fp_line
			(start 0.67945 0.3048)
			(end 0.120396 0.3048)
			(stroke
				(width 0.1)
				(type default)
			)
			(layer "F.Fab")
		)
		(fp_line
			(start 0.120396 0.3048)
			(end 0.120396 0.2794)
			(stroke
				(width 0.1)
				(type default)
			)
			(layer "F.Fab")
		)
		(fp_line
			(start -0.12065 0.3048)
			(end -0.67945 0.3048)
			(stroke
				(width 0.1)
				(type default)
			)
			(layer "F.Fab")
		)
		(fp_line
			(start -0.67945 0.3048)
			(end -0.67945 -0.305054)
			(stroke
				(width 0.1)
				(type default)
			)
			(layer "F.Fab")
		)
		(pad "1" smd circle
			(at -0.40005 0 90)
			(size 0 0)
			(layers "F.Cu" "F.Mask" "F.Paste")
			(net "PVDD11_S3_P0_PVCC")
		)
		(pad "2" smd circle
			(at 0.40005 0 90)
			(size 0 0)
			(layers "F.Cu" "F.Mask" "F.Paste")
			(net "P3V3_AUX")
		)
	)
)
